FILE_TYPE = MULTI_PHYS_TABLE;

PART 'RS53319LR'

{========================================================================================}
:VALUE       | PART_TYPE | MATERIAL | PART_NUMBER    = STANDARD | LIFECYCLE          | PART_NUMBER   | JEDEC_TYPE  | DESCRIPTION             | MANUFTR | MANUF_PN    | RD_CMPLS_LVL | CMPLS_LVL | FROM_PJ    | CLASS | DIP_SMD | DATA                | EE_CHECK_LIST | FP_ECN | PSL | CREATOR | STATUS | MSD | ESD_CDM | ESD_HBM | ESD_MM | PIN_LENGTH_SHORT_PIN | PIN_LENGTH_LONG_PIN | CREATEDAY  ;
{========================================================================================}
 'RS53319LR' | 'SMLF'    | 'IC'     | 'AL053319002'(!) = ''       | ''               | 'AL053319002' |'QFN21_4X3'| 'IC(21P)RS53319LR(QFN)' | 'RDS'   | 'RS53319LR' | 'EP(V1)'     | 'EP(V1)'  | 'F0T-GREG' | 'IC'  | ''      | 'RDS_RS53319LR.pdf' | ''            | ''     | ''  | ''      | ''     | ''  | ''      | ''      | ''     | '0 MILS'             | '0 MILS'            | '20220510'
 'RS53319LR' | 'SMLF'    | 'EMPTY'  | 'AL053319002'(!) = ''       | ''               | 'AL053319002' |'QFN21_4X3'| 'IC(21P)RS53319LR(QFN)' | 'RDS'   | 'RS53319LR' | 'EP(V1)'     | 'EP(V1)'  | 'F0T-GREG' | 'IC'  | ''      | 'RDS_RS53319LR.pdf' | ''            | ''     | ''  | ''      | ''     | ''  | ''      | ''      | ''     | '0 MILS'             | '0 MILS'            | '20220510'

END_PART

END.

